# BASEBOARD_FAB2 (Tioga Pass) — schematic netlist excerpt (pin names and nets, part order shuffled) for the footprints in the layout excerpt that follows; sources: Cadence DE-HDL packaged netlist, KiCad conversion of Wiwynn_Tioga_Pass_MB.brd

CT22  CAP  1000PF 50V 10% X7R  pkg 0402LF  page 207 : A = A_TSENSE_PVCCIN_CPU1 ; B = GND
C3L22  CAP_A  22.0UF 4V 20% X6S  pkg 0603V  page 132 : A = PVNN_PCH_STBY ; B = GND
R6R6  RES  0.0 5% CHIP  pkg 0402  page 202 : A = VR_PVCCIN_CPU0_PH2_VCIN ; B = P5V_STBY

(kicad_pcb
	(version 20260206)
	(generator "pcbnew")
	(generator_version "10.0")
	(general
		(thickness 1.6)
		(legacy_teardrops no)
	)
	(paper "A4")
	(title_block
		(title "Wiwynn_Tioga_Pass_MB.brd")
		(comment 1 "Tioga Pass / footprints 3578-3580 of 4770")
	)
	(layers
		(0 "F.Cu" signal "TOP")
		(4 "In1.Cu" signal "L2GND")
		(6 "In2.Cu" signal "L3")
		(8 "In3.Cu" signal "L4GND")
		(10 "In4.Cu" signal "L5")
		(12 "In5.Cu" signal "L6GND")
		(14 "In6.Cu" signal "L7VCC")
		(16 "In7.Cu" signal "L8VCC")
		(18 "In8.Cu" signal "L9GND")
		(20 "In9.Cu" signal "L10")
		(22 "In10.Cu" signal "L11GND")
		(24 "In11.Cu" signal "L12")
		(26 "In12.Cu" signal "L13GND")
		(2 "B.Cu" signal "BOTTOM")
		(9 "F.Adhes" user "F.Adhesive")
		(11 "B.Adhes" user "B.Adhesive")
		(13 "F.Paste" user "Package Geometry/Pastemask Top")
		(15 "B.Paste" user "Package Geometry/Pastemask Bottom")
		(5 "F.SilkS" user "Ref Des/Silkscreen Top")
		(7 "B.SilkS" user "Ref Des/Silkscreen Bottom")
		(1 "F.Mask" user "Board Geometry/Soldermask Top")
		(3 "B.Mask" user "Board Geometry/Soldermask Bottom")
		(17 "Dwgs.User" user "User.Drawings")
		(19 "Cmts.User" user "User.Comments")
		(21 "Eco1.User" user "User.Eco1")
		(23 "Eco2.User" user "User.Eco2")
		(25 "Edge.Cuts" user "Board Geometry/Outline")
		(27 "Margin" user)
		(31 "F.CrtYd" user "Package Geometry/Place Bound Top")
		(29 "B.CrtYd" user "Package Geometry/Place Bound Bottom")
		(35 "F.Fab" user "Ref Des/Assembly Top")
		(33 "B.Fab" user "Ref Des/Assembly Bottom")
	)
	(footprint ""
		(layer "B.Cu")
		(at 30.988 -55.7276 180)
		(property "Reference" "CT22"
			(at 0.8382 -0.84963 180)
			(unlocked yes)
			(layer "B.SilkS")
			(effects
				(font
					(size 0.7874 0.5842)
					(thickness 0.1524)
				)
				(justify left mirror)
			)
		)
		(property "Value" ""
			(at 0 0 0)
			(layer "B.Fab")
			(effects
				(font
					(size 1.27 1.27)
				)
				(justify mirror)
			)
		)
		(duplicate_pad_numbers_are_jumpers no)
		(fp_poly
			(pts
				(xy -0.3048 -0.1016) (xy -0.3048 0.9906) (xy 0.3048 0.9906) (xy 0.3048 -0.1016)
			)
			(stroke
				(width 0)
				(type default)
			)
			(fill no)
			(layer "B.CrtYd")
		)
		(fp_line
			(start 0.3048 0.9906)
			(end -0.3048 0.9906)
			(stroke
				(width 0.1)
				(type default)
			)
			(layer "B.Fab")
		)
		(fp_line
			(start 0.3048 -0.1016)
			(end 0.3048 0.9906)
			(stroke
				(width 0.1)
				(type default)
			)
			(layer "B.Fab")
		)
		(fp_line
			(start -0.3048 0.9906)
			(end -0.3048 -0.1016)
			(stroke
				(width 0.1)
				(type default)
			)
			(layer "B.Fab")
		)
		(fp_line
			(start -0.3048 -0.1016)
			(end 0.3048 -0.1016)
			(stroke
				(width 0.1)
				(type default)
			)
			(layer "B.Fab")
		)
		(pad "1" smd rect
			(at 0 0)
			(size 0.508 0.508)
			(layers "B.Cu" "B.Mask" "B.Paste")
			(net "A_TSENSE_PVCCIN_CPU1")
		)
		(pad "2" smd rect
			(at 0 0.889)
			(size 0.508 0.508)
			(layers "B.Cu" "B.Mask" "B.Paste")
			(net "GND")
		)
		(zone
			(layer "B.Cu")
			(hatch none 0.5)
			(connect_pads
				(clearance 0)
			)
			(min_thickness 0.25)
			(keepout
				(tracks not_allowed)
				(vias allowed)
				(pads allowed)
				(copperpour not_allowed)
				(footprints allowed)
			)
			(placement
				(enabled no)
				(sheetname "")
			)
			(fill
				(thermal_gap 0.5)
				(thermal_bridge_width 0.5)
				(island_removal_mode 0)
			)
			(polygon
				(pts
					(xy 30.734 -56.3626) (xy 31.242 -56.3626) (xy 31.242 -55.9816) (xy 30.734 -55.9816)
				)
			)
		)
		(zone
			(layer "B.Cu")
			(hatch none 0.5)
			(connect_pads
				(clearance 0)
			)
			(min_thickness 0.25)
			(keepout
				(tracks allowed)
				(vias not_allowed)
				(pads allowed)
				(copperpour not_allowed)
				(footprints allowed)
			)
			(placement
				(enabled no)
				(sheetname "")
			)
			(fill
				(thermal_gap 0.5)
				(thermal_bridge_width 0.5)
				(island_removal_mode 0)
			)
			(polygon
				(pts
					(xy 30.734 -55.9816) (xy 31.242 -55.9816) (xy 31.242 -56.3626) (xy 30.734 -56.3626)
				)
			)
		)
	)
	(footprint ""
		(layer "B.Cu")
		(at 197.239128 -62.659006 90)
		(property "Reference" "R6R6"
			(at 0 0 90)
			(layer "B.SilkS")
			(hide yes)
			(effects
				(font
					(size 1.27 1.27)
				)
				(justify mirror)
			)
		)
		(property "Value" ""
			(at 0 0 90)
			(layer "B.Fab")
			(effects
				(font
					(size 1.27 1.27)
				)
				(justify mirror)
			)
		)
		(duplicate_pad_numbers_are_jumpers no)
		(fp_rect
			(start 0.2794 -0.1016)
			(end -0.2794 0.9906)
			(stroke
				(width 0)
				(type default)
			)
			(fill no)
			(layer "B.CrtYd")
		)
		(fp_line
			(start 0.2794 -0.1016)
			(end 0.2794 0.9906)
			(stroke
				(width 0.1)
				(type default)
			)
			(layer "B.Fab")
		)
		(fp_line
			(start -0.2794 -0.1016)
			(end 0.2794 -0.1016)
			(stroke
				(width 0.1)
				(type default)
			)
			(layer "B.Fab")
		)
		(fp_line
			(start 0.2794 0.9906)
			(end -0.2794 0.9906)
			(stroke
				(width 0.1)
				(type default)
			)
			(layer "B.Fab")
		)
		(fp_line
			(start -0.2794 0.9906)
			(end -0.2794 -0.1016)
			(stroke
				(width 0.1)
				(type default)
			)
			(layer "B.Fab")
		)
		(pad "1" smd rect
			(at 0 0 270)
			(size 0.508 0.508)
			(layers "B.Cu" "B.Mask" "B.Paste")
			(net "VR_PVCCIN_CPU0_PH2_VCIN")
		)
		(pad "2" smd rect
			(at 0 0.889 270)
			(size 0.508 0.508)
			(layers "B.Cu" "B.Mask" "B.Paste")
			(net "P5V_STBY")
		)
		(zone
			(layer "B.Cu")
			(hatch none 0.5)
			(connect_pads
				(clearance 0)
			)
			(min_thickness 0.25)
			(keepout
				(tracks allowed)
				(vias not_allowed)
				(pads allowed)
				(copperpour not_allowed)
				(footprints allowed)
			)
			(placement
				(enabled no)
				(sheetname "")
			)
			(fill
				(thermal_gap 0.5)
				(thermal_bridge_width 0.5)
				(island_removal_mode 0)
			)
			(polygon
				(pts
					(xy 197.493128 -62.913006) (xy 197.493128 -62.405006) (xy 197.874128 -62.405006) (xy 197.874128 -62.913006)
				)
			)
		)
		(zone
			(layer "B.Cu")
			(hatch none 0.5)
			(connect_pads
				(clearance 0)
			)
			(min_thickness 0.25)
			(keepout
				(tracks not_allowed)
				(vias allowed)
				(pads allowed)
				(copperpour not_allowed)
				(footprints allowed)
			)
			(placement
				(enabled no)
				(sheetname "")
			)
			(fill
				(thermal_gap 0.5)
				(thermal_bridge_width 0.5)
				(island_removal_mode 0)
			)
			(polygon
				(pts
					(xy 197.493128 -62.913006) (xy 197.493128 -62.405006) (xy 197.874128 -62.405006) (xy 197.874128 -62.913006)
				)
			)
		)
	)
	(footprint ""
		(layer "B.Cu")
		(at 375.285 -138.1125)
		(property "Reference" "C3L22"
			(at 0 0 0)
			(layer "B.SilkS")
			(hide yes)
			(effects
				(font
					(size 1.27 1.27)
				)
				(justify mirror)
			)
		)
		(property "Value" ""
			(at 0 0 0)
			(layer "B.Fab")
			(effects
				(font
					(size 1.27 1.27)
				)
				(justify mirror)
			)
		)
		(duplicate_pad_numbers_are_jumpers no)
		(fp_poly
			(pts
				(xy 0.4953 -0.2032) (xy -0.4953 -0.2032) (xy -0.4953 1.6002) (xy 0.4953 1.6002)
			)
			(stroke
				(width 0)
				(type default)
			)
			(fill no)
			(layer "B.CrtYd")
		)
		(fp_line
			(start -0.4953 -0.2032)
			(end -0.4953 1.6002)
			(stroke
				(width 0.1)
				(type default)
			)
			(layer "B.Fab")
		)
		(fp_line
			(start -0.4953 1.6002)
			(end 0.4953 1.6002)
			(stroke
				(width 0.1)
				(type default)
			)
			(layer "B.Fab")
		)
		(fp_line
			(start 0.4953 -0.2032)
			(end -0.4953 -0.2032)
			(stroke
				(width 0.1)
				(type default)
			)
			(layer "B.Fab")
		)
		(fp_line
			(start 0.4953 1.6002)
			(end 0.4953 -0.2032)
			(stroke
				(width 0.1)
				(type default)
			)
			(layer "B.Fab")
		)
		(pad "1" smd rect
			(at 0 0 180)
			(size 0.762 0.889)
			(layers "B.Cu" "B.Mask" "B.Paste")
			(net "PVNN_PCH_STBY")
		)
		(pad "2" smd rect
			(at 0 1.397 180)
			(size 0.762 0.889)
			(layers "B.Cu" "B.Mask" "B.Paste")
			(net "GND")
		)
		(zone
			(layer "B.Cu")
			(hatch none 0.5)
			(connect_pads
				(clearance 0)
			)
			(min_thickness 0.25)
			(keepout
				(tracks not_allowed)
				(vias allowed)
				(pads allowed)
				(copperpour not_allowed)
				(footprints allowed)
			)
			(placement
				(enabled no)
				(sheetname "")
			)
			(fill
				(thermal_gap 0.5)
				(thermal_bridge_width 0.5)
				(island_removal_mode 0)
			)
			(polygon
				(pts
					(xy 375.666 -137.668) (xy 374.904 -137.668) (xy 374.904 -137.16) (xy 375.666 -137.16)
				)
			)
		)
	)
)
